(kicad_pcb
	(version 20260206)
	(generator "pcbnew")
	(generator_version "10.0")
	(general
		(thickness 1.6)
		(legacy_teardrops no)
	)
	(paper "A4")
	(title_block
		(title "v1-chassis-manager — T6M_CM_d_v01_1031_1645.brd")
		(comment 1 "Open CloudServer (Microsoft) / footprints 121-129 of 2512")
	)
	(layers
		(0 "F.Cu" signal "TOP")
		(4 "In1.Cu" signal "GND1")
		(6 "In2.Cu" signal "IN1")
		(8 "In3.Cu" signal "VCC1")
		(10 "In4.Cu" signal "VCC2")
		(12 "In5.Cu" signal "GND2")
		(14 "In6.Cu" signal "IN2")
		(16 "In7.Cu" signal "IN3")
		(18 "In8.Cu" signal "GND3")
		(2 "B.Cu" signal "BOTTOM")
		(9 "F.Adhes" user "F.Adhesive")
		(11 "B.Adhes" user "B.Adhesive")
		(13 "F.Paste" user "Package Geometry/Pastemask Top")
		(15 "B.Paste" user "Package Geometry/Pastemask Bottom")
		(5 "F.SilkS" user "Ref Des/Silkscreen Top")
		(7 "B.SilkS" user "Ref Des/Silkscreen Bottom")
		(1 "F.Mask" user "Board Geometry/Soldermask Top")
		(3 "B.Mask" user "Board Geometry/Soldermask Bottom")
		(17 "Dwgs.User" user "User.Drawings")
		(19 "Cmts.User" user "User.Comments")
		(21 "Eco1.User" user "User.Eco1")
		(23 "Eco2.User" user "User.Eco2")
		(25 "Edge.Cuts" user "Board Geometry/Outline")
		(27 "Margin" user)
		(31 "F.CrtYd" user "Package Geometry/Place Bound Top")
		(29 "B.CrtYd" user "Package Geometry/Place Bound Bottom")
		(35 "F.Fab" user "Ref Des/Assembly Top")
		(33 "B.Fab" user "Ref Des/Assembly Bottom")
	)
	(footprint ""
		(layer "F.Cu")
		(at 93.532452 -131.560062 90)
		(property "Reference" "R1104"
			(at -2.83718 -0.924306 90)
			(unlocked yes)
			(layer "F.SilkS")
			(effects
				(font
					(size 0.7874 0.5842)
					(thickness 0.1524)
				)
				(justify left)
			)
		)
		(property "Value" ""
			(at 0 0 90)
			(layer "F.Fab")
			(effects
				(font
					(size 1.27 1.27)
				)
			)
		)
		(duplicate_pad_numbers_are_jumpers no)
		(fp_line
			(start 0.7874 -0.4064)
			(end 0.7874 0.4064)
			(stroke
				(width 0.1524)
				(type default)
			)
			(layer "F.SilkS")
		)
		(fp_line
			(start -0.7874 -0.4064)
			(end 0.7874 -0.4064)
			(stroke
				(width 0.1524)
				(type default)
			)
			(layer "F.SilkS")
		)
		(fp_line
			(start 0.7874 0.4064)
			(end -0.7874 0.4064)
			(stroke
				(width 0.1524)
				(type default)
			)
			(layer "F.SilkS")
		)
		(fp_line
			(start -0.7874 0.4064)
			(end -0.7874 -0.4064)
			(stroke
				(width 0.1524)
				(type default)
			)
			(layer "F.SilkS")
		)
		(fp_poly
			(pts
				(xy -0.508 0.2794) (xy -0.508 0.2286) (xy -0.635 0.2286) (xy -0.635 -0.254) (xy -0.5334 -0.254)
				(xy -0.5334 -0.2794) (xy 0.5334 -0.2794) (xy 0.5334 -0.254) (xy 0.635 -0.254) (xy 0.635 0.254) (xy 0.5334 0.254)
				(xy 0.5334 0.2794)
			)
			(stroke
				(width 0)
				(type default)
			)
			(fill no)
			(layer "F.CrtYd")
		)
		(pad "1" smd rect
			(at 0.40005 0 90)
			(size 0.4572 0.508)
			(layers "F.Cu" "F.Mask" "F.Paste")
			(net "GND")
		)
		(pad "2" smd rect
			(at -0.40005 0 90)
			(size 0.4572 0.508)
			(layers "F.Cu" "F.Mask" "F.Paste")
			(net "FM_CPLD_NODE1_P1V05_SUS_EN")
		)
	)
	(footprint ""
		(layer "F.Cu")
		(at 133.674612 -158.79953)
		(property "Reference" "U127"
			(at -62.464442 109.000798 90)
			(unlocked yes)
			(layer "F.SilkS")
			(effects
				(font
					(size 0.7874 0.5842)
					(thickness 0.1524)
				)
			)
		)
		(property "Value" ""
			(at 0 0 0)
			(layer "F.Fab")
			(effects
				(font
					(size 1.27 1.27)
				)
			)
		)
		(duplicate_pad_numbers_are_jumpers no)
		(fp_line
			(start -1.651 -1.905)
			(end 1.651 -1.905)
			(stroke
				(width 0.1524)
				(type default)
			)
			(layer "F.SilkS")
		)
		(fp_line
			(start -1.651 1.905)
			(end -1.651 -1.905)
			(stroke
				(width 0.1524)
				(type default)
			)
			(layer "F.SilkS")
		)
		(fp_line
			(start 1.651 -1.905)
			(end 1.651 1.905)
			(stroke
				(width 0.1524)
				(type default)
			)
			(layer "F.SilkS")
		)
		(fp_line
			(start 1.651 1.905)
			(end -1.651 1.905)
			(stroke
				(width 0.1524)
				(type default)
			)
			(layer "F.SilkS")
		)
		(fp_poly
			(pts
				(xy -1.524 0.7112) (xy -1.524 1.7526) (xy -0.508 1.7526) (xy -0.508 0.6985) (xy 0.508 0.6985) (xy 0.508 1.7526)
				(xy 1.524 1.7526) (xy 1.524 0.6985) (xy 1.524 -0.6985) (xy 0.508 -0.6985) (xy 0.508 -1.7526) (xy -0.508 -1.7526)
				(xy -0.508 -0.6985) (xy -1.524 -0.6985) (xy -1.524 0.6985)
			)
			(stroke
				(width 0)
				(type default)
			)
			(fill no)
			(layer "F.CrtYd")
		)
		(fp_text user "G"
			(at -2.350008 2.76733 0)
			(unlocked yes)
			(layer "F.SilkS")
			(effects
				(font
					(size 0.635 0.4064)
					(thickness 0.1524)
				)
			)
		)
		(fp_text user "D"
			(at 0.254762 -2.4765 0)
			(unlocked yes)
			(layer "F.SilkS")
			(effects
				(font
					(size 0.635 0.4064)
					(thickness 0.1524)
				)
			)
		)
		(fp_text user "S"
			(at 0.869696 2.623566 0)
			(unlocked yes)
			(layer "F.SilkS")
			(effects
				(font
					(size 0.635 0.4064)
					(thickness 0.1524)
				)
			)
		)
		(pad "D" smd rect
			(at 0 -1.1176)
			(size 1.016 1.27)
			(layers "F.Cu" "F.Mask" "F.Paste")
			(net "I2C_PSU3_SDA")
		)
		(pad "G" smd rect
			(at -1.016 1.1176)
			(size 1.016 1.27)
			(layers "F.Cu" "F.Mask" "F.Paste")
			(net "PMBUS3_EN")
		)
		(pad "S" smd rect
			(at 1.016 1.1176)
			(size 1.016 1.27)
			(layers "F.Cu" "F.Mask" "F.Paste")
			(net "I2C_PSU3_SDA_MOS")
		)
	)
	(footprint ""
		(layer "F.Cu")
		(at 166.28364 -188.19749 -90)
		(property "Reference" "R844"
			(at -0.95631 -0.24003 90)
			(unlocked yes)
			(layer "F.SilkS")
			(effects
				(font
					(size 0.7874 0.5842)
					(thickness 0.1524)
				)
				(justify left)
			)
		)
		(property "Value" ""
			(at 0 0 270)
			(layer "F.Fab")
			(effects
				(font
					(size 1.27 1.27)
				)
			)
		)
		(duplicate_pad_numbers_are_jumpers no)
		(fp_line
			(start -0.7874 0.4064)
			(end -0.7874 -0.4064)
			(stroke
				(width 0.1524)
				(type default)
			)
			(layer "F.SilkS")
		)
		(fp_line
			(start 0.7874 0.4064)
			(end -0.7874 0.4064)
			(stroke
				(width 0.1524)
				(type default)
			)
			(layer "F.SilkS")
		)
		(fp_line
			(start -0.7874 -0.4064)
			(end 0.7874 -0.4064)
			(stroke
				(width 0.1524)
				(type default)
			)
			(layer "F.SilkS")
		)
		(fp_line
			(start 0.7874 -0.4064)
			(end 0.7874 0.4064)
			(stroke
				(width 0.1524)
				(type default)
			)
			(layer "F.SilkS")
		)
		(fp_poly
			(pts
				(xy -0.508 0.2794) (xy -0.508 0.2286) (xy -0.635 0.2286) (xy -0.635 -0.254) (xy -0.5334 -0.254)
				(xy -0.5334 -0.2794) (xy 0.5334 -0.2794) (xy 0.5334 -0.254) (xy 0.635 -0.254) (xy 0.635 0.254) (xy 0.5334 0.254)
				(xy 0.5334 0.2794)
			)
			(stroke
				(width 0)
				(type default)
			)
			(fill no)
			(layer "F.CrtYd")
		)
		(pad "1" smd rect
			(at 0.40005 0 270)
			(size 0.4572 0.508)
			(layers "F.Cu" "F.Mask" "F.Paste")
			(net "I2C_PDB_SDA")
		)
		(pad "2" smd rect
			(at -0.40005 0 270)
			(size 0.4572 0.508)
			(layers "F.Cu" "F.Mask" "F.Paste")
			(net "I2C_PDB_R_SDA")
		)
	)
	(footprint ""
		(layer "F.Cu")
		(at 129.100834 -65.553336 90)
		(property "Reference" "U31"
			(at 3.312414 -2.070862 0)
			(unlocked yes)
			(layer "F.SilkS")
			(effects
				(font
					(size 0.7874 0.5842)
					(thickness 0.1524)
				)
				(justify left)
			)
		)
		(property "Value" ""
			(at 0 0 90)
			(layer "F.Fab")
			(effects
				(font
					(size 1.27 1.27)
				)
			)
		)
		(duplicate_pad_numbers_are_jumpers no)
		(fp_line
			(start 2.690114 -2.599944)
			(end 2.690114 2.599944)
			(stroke
				(width 0.1524)
				(type default)
			)
			(layer "F.SilkS")
		)
		(fp_line
			(start -2.690114 -2.599944)
			(end 2.690114 -2.599944)
			(stroke
				(width 0.1524)
				(type default)
			)
			(layer "F.SilkS")
		)
		(fp_line
			(start -2.690114 -0.40005)
			(end -2.690114 -2.599944)
			(stroke
				(width 0.1524)
				(type default)
			)
			(layer "F.SilkS")
		)
		(fp_line
			(start -1.905 0)
			(end -2.690114 -0.40005)
			(stroke
				(width 0.1524)
				(type default)
			)
			(layer "F.SilkS")
		)
		(fp_line
			(start -2.690114 0.40005)
			(end -1.905 0)
			(stroke
				(width 0.1524)
				(type default)
			)
			(layer "F.SilkS")
		)
		(fp_line
			(start 2.690114 2.599944)
			(end -2.690114 2.599944)
			(stroke
				(width 0.1524)
				(type default)
			)
			(layer "F.SilkS")
		)
		(fp_line
			(start -2.690114 2.599944)
			(end -2.690114 0.40005)
			(stroke
				(width 0.1524)
				(type default)
			)
			(layer "F.SilkS")
		)
		(fp_circle
			(center -1.9304 2.0066)
			(end -1.9304 2.2606)
			(stroke
				(width 0.1524)
				(type default)
			)
			(fill no)
			(layer "F.SilkS")
		)
		(fp_poly
			(pts
				(xy -2.1844 4.4958) (xy -2.1844 2.5908) (xy -2.6924 2.5908) (xy -2.6924 -2.5908) (xy -2.1844 -2.5908)
				(xy -2.1844 -4.4958) (xy 2.1844 -4.4958) (xy 2.1844 -2.5908) (xy 2.667 -2.5908) (xy 2.667 2.5908)
				(xy 2.1844 2.5908) (xy 2.1844 4.4958)
			)
			(stroke
				(width 0)
				(type default)
			)
			(fill no)
			(layer "F.CrtYd")
		)
		(pad "1" smd rect
			(at -1.905 3.636518 90)
			(size 0.5588 1.7272)
			(layers "F.Cu" "F.Mask" "F.Paste")
			(net "SATA_SPI_CS_NODE1")
		)
		(pad "2" smd rect
			(at -0.635 3.636518 90)
			(size 0.5588 1.7272)
			(layers "F.Cu" "F.Mask" "F.Paste")
			(net "SATA_SPI_DI_NODE1_R")
		)
		(pad "3" smd rect
			(at 0.635 3.636518 90)
			(size 0.5588 1.7272)
			(layers "F.Cu" "F.Mask" "F.Paste")
			(net "N21116716")
		)
		(pad "4" smd rect
			(at 1.905 3.636518 90)
			(size 0.5588 1.7272)
			(layers "F.Cu" "F.Mask" "F.Paste")
			(net "GND")
		)
		(pad "5" smd rect
			(at 1.905 -3.636518 90)
			(size 0.5588 1.7272)
			(layers "F.Cu" "F.Mask" "F.Paste")
			(net "SATA_SPI_DO_NODE1")
		)
		(pad "6" smd rect
			(at 0.635 -3.636518 90)
			(size 0.5588 1.7272)
			(layers "F.Cu" "F.Mask" "F.Paste")
			(net "SATA_SPI_CLK_NODE1")
		)
		(pad "7" smd rect
			(at -0.635 -3.636518 90)
			(size 0.5588 1.7272)
			(layers "F.Cu" "F.Mask" "F.Paste")
			(net "N21116716")
		)
		(pad "8" smd rect
			(at -1.905 -3.636518 90)
			(size 0.5588 1.7272)
			(layers "F.Cu" "F.Mask" "F.Paste")
			(net "P3V3_NODE1")
		)
	)
	(footprint ""
		(layer "F.Cu")
		(at 54.72176 -178.804824 180)
		(property "Reference" "U98"
			(at 5.879084 -132.66293 90)
			(unlocked yes)
			(layer "F.SilkS")
			(effects
				(font
					(size 0.7874 0.5842)
					(thickness 0.1524)
				)
			)
		)
		(property "Value" ""
			(at 0 0 180)
			(layer "F.Fab")
			(effects
				(font
					(size 1.27 1.27)
				)
			)
		)
		(duplicate_pad_numbers_are_jumpers no)
		(fp_line
			(start 1.651 1.905)
			(end -1.651 1.905)
			(stroke
				(width 0.1524)
				(type default)
			)
			(layer "F.SilkS")
		)
		(fp_line
			(start 1.651 -1.905)
			(end 1.651 1.905)
			(stroke
				(width 0.1524)
				(type default)
			)
			(layer "F.SilkS")
		)
		(fp_line
			(start -1.651 1.905)
			(end -1.651 -1.905)
			(stroke
				(width 0.1524)
				(type default)
			)
			(layer "F.SilkS")
		)
		(fp_line
			(start -1.651 -1.905)
			(end 1.651 -1.905)
			(stroke
				(width 0.1524)
				(type default)
			)
			(layer "F.SilkS")
		)
		(fp_poly
			(pts
				(xy -1.524 0.7112) (xy -1.524 1.7526) (xy -0.508 1.7526) (xy -0.508 0.6985) (xy 0.508 0.6985) (xy 0.508 1.7526)
				(xy 1.524 1.7526) (xy 1.524 0.6985) (xy 1.524 -0.6985) (xy 0.508 -0.6985) (xy 0.508 -1.7526) (xy -0.508 -1.7526)
				(xy -0.508 -0.6985) (xy -1.524 -0.6985) (xy -1.524 0.6985)
			)
			(stroke
				(width 0)
				(type default)
			)
			(fill no)
			(layer "F.CrtYd")
		)
		(fp_text user "S"
			(at 0.032258 2.201418 90)
			(unlocked yes)
			(layer "F.SilkS")
			(effects
				(font
					(size 0.635 0.4064)
					(thickness 0.1524)
				)
			)
		)
		(fp_text user "D"
			(at -0.185674 -2.48793 0)
			(unlocked yes)
			(layer "F.SilkS")
			(effects
				(font
					(size 0.635 0.4064)
					(thickness 0.1524)
				)
			)
		)
		(fp_text user "G"
			(at -1.905 2.69875 0)
			(unlocked yes)
			(layer "F.SilkS")
			(effects
				(font
					(size 0.635 0.4064)
					(thickness 0.1524)
				)
			)
		)
		(pad "D" smd rect
			(at 0 -1.1176 180)
			(size 1.016 1.27)
			(layers "F.Cu" "F.Mask" "F.Paste")
			(net "PSU_DC_OK_N")
		)
		(pad "G" smd rect
			(at -1.016 1.1176 180)
			(size 1.016 1.27)
			(layers "F.Cu" "F.Mask" "F.Paste")
			(net "PSU4_DC_OK_R_BUF")
		)
		(pad "S" smd rect
			(at 1.016 1.1176 180)
			(size 1.016 1.27)
			(layers "F.Cu" "F.Mask" "F.Paste")
			(net "GND")
		)
	)
	(footprint ""
		(layer "F.Cu")
		(at 123.70816 -164.491416 180)
		(property "Reference" "R680"
			(at -30.092904 -46.17974 0)
			(unlocked yes)
			(layer "F.SilkS")
			(effects
				(font
					(size 0.7874 0.5842)
					(thickness 0.1524)
				)
				(justify left)
			)
		)
		(property "Value" ""
			(at 0 0 180)
			(layer "F.Fab")
			(effects
				(font
					(size 1.27 1.27)
				)
			)
		)
		(duplicate_pad_numbers_are_jumpers no)
		(fp_line
			(start 0.7874 0.4064)
			(end -0.7874 0.4064)
			(stroke
				(width 0.1524)
				(type default)
			)
			(layer "F.SilkS")
		)
		(fp_line
			(start 0.7874 -0.4064)
			(end 0.7874 0.4064)
			(stroke
				(width 0.1524)
				(type default)
			)
			(layer "F.SilkS")
		)
		(fp_line
			(start -0.7874 0.4064)
			(end -0.7874 -0.4064)
			(stroke
				(width 0.1524)
				(type default)
			)
			(layer "F.SilkS")
		)
		(fp_line
			(start -0.7874 -0.4064)
			(end 0.7874 -0.4064)
			(stroke
				(width 0.1524)
				(type default)
			)
			(layer "F.SilkS")
		)
		(fp_poly
			(pts
				(xy -0.508 0.2794) (xy -0.508 0.2286) (xy -0.635 0.2286) (xy -0.635 -0.254) (xy -0.5334 -0.254)
				(xy -0.5334 -0.2794) (xy 0.5334 -0.2794) (xy 0.5334 -0.254) (xy 0.635 -0.254) (xy 0.635 0.254) (xy 0.5334 0.254)
				(xy 0.5334 0.2794)
			)
			(stroke
				(width 0)
				(type default)
			)
			(fill no)
			(layer "F.CrtYd")
		)
		(pad "1" smd rect
			(at 0.40005 0 180)
			(size 0.4572 0.508)
			(layers "F.Cu" "F.Mask" "F.Paste")
			(net "COM3_WAKEUP")
		)
		(pad "2" smd rect
			(at -0.40005 0 180)
			(size 0.4572 0.508)
			(layers "F.Cu" "F.Mask" "F.Paste")
			(net "P3V3_NODE1")
		)
	)
	(footprint ""
		(layer "F.Cu")
		(at 142.724886 -51.476656 90)
		(property "Reference" "R1018"
			(at 16.324326 30.452822 90)
			(unlocked yes)
			(layer "F.SilkS")
			(effects
				(font
					(size 0.7874 0.5842)
					(thickness 0.1524)
				)
				(justify left)
			)
		)
		(property "Value" ""
			(at 0 0 90)
			(layer "F.Fab")
			(effects
				(font
					(size 1.27 1.27)
				)
			)
		)
		(duplicate_pad_numbers_are_jumpers no)
		(fp_line
			(start 0.7874 -0.4064)
			(end 0.7874 0.4064)
			(stroke
				(width 0.1524)
				(type default)
			)
			(layer "F.SilkS")
		)
		(fp_line
			(start -0.7874 -0.4064)
			(end 0.7874 -0.4064)
			(stroke
				(width 0.1524)
				(type default)
			)
			(layer "F.SilkS")
		)
		(fp_line
			(start 0.7874 0.4064)
			(end -0.7874 0.4064)
			(stroke
				(width 0.1524)
				(type default)
			)
			(layer "F.SilkS")
		)
		(fp_line
			(start -0.7874 0.4064)
			(end -0.7874 -0.4064)
			(stroke
				(width 0.1524)
				(type default)
			)
			(layer "F.SilkS")
		)
		(fp_poly
			(pts
				(xy -0.508 0.2794) (xy -0.508 0.2286) (xy -0.635 0.2286) (xy -0.635 -0.254) (xy -0.5334 -0.254)
				(xy -0.5334 -0.2794) (xy 0.5334 -0.2794) (xy 0.5334 -0.254) (xy 0.635 -0.254) (xy 0.635 0.254) (xy 0.5334 0.254)
				(xy 0.5334 0.2794)
			)
			(stroke
				(width 0)
				(type default)
			)
			(fill no)
			(layer "F.CrtYd")
		)
		(pad "1" smd rect
			(at 0.40005 0 90)
			(size 0.4572 0.508)
			(layers "F.Cu" "F.Mask" "F.Paste")
			(net "GND")
		)
		(pad "2" smd rect
			(at -0.40005 0 90)
			(size 0.4572 0.508)
			(layers "F.Cu" "F.Mask" "F.Paste")
			(net "UART_RTS_P2_N")
		)
	)
	(footprint ""
		(layer "F.Cu")
		(at 129.06756 -188.126624 -90)
		(property "Reference" "R998"
			(at -4.949444 0.583438 90)
			(unlocked yes)
			(layer "F.SilkS")
			(effects
				(font
					(size 0.7874 0.5842)
					(thickness 0.1524)
				)
				(justify left)
			)
		)
		(property "Value" ""
			(at 0 0 270)
			(layer "F.Fab")
			(effects
				(font
					(size 1.27 1.27)
				)
			)
		)
		(duplicate_pad_numbers_are_jumpers no)
		(fp_line
			(start -0.7874 0.4064)
			(end -0.7874 -0.4064)
			(stroke
				(width 0.1524)
				(type default)
			)
			(layer "F.SilkS")
		)
		(fp_line
			(start 0.7874 0.4064)
			(end -0.7874 0.4064)
			(stroke
				(width 0.1524)
				(type default)
			)
			(layer "F.SilkS")
		)
		(fp_line
			(start -0.7874 -0.4064)
			(end 0.7874 -0.4064)
			(stroke
				(width 0.1524)
				(type default)
			)
			(layer "F.SilkS")
		)
		(fp_line
			(start 0.7874 -0.4064)
			(end 0.7874 0.4064)
			(stroke
				(width 0.1524)
				(type default)
			)
			(layer "F.SilkS")
		)
		(fp_poly
			(pts
				(xy -0.508 0.2794) (xy -0.508 0.2286) (xy -0.635 0.2286) (xy -0.635 -0.254) (xy -0.5334 -0.254)
				(xy -0.5334 -0.2794) (xy 0.5334 -0.2794) (xy 0.5334 -0.254) (xy 0.635 -0.254) (xy 0.635 0.254) (xy 0.5334 0.254)
				(xy 0.5334 0.2794)
			)
			(stroke
				(width 0)
				(type default)
			)
			(fill no)
			(layer "F.CrtYd")
		)
		(pad "1" smd rect
			(at 0.40005 0 270)
			(size 0.4572 0.508)
			(layers "F.Cu" "F.Mask" "F.Paste")
			(net "UART_T10_NODE4_RXD")
		)
		(pad "2" smd rect
			(at -0.40005 0 270)
			(size 0.4572 0.508)
			(layers "F.Cu" "F.Mask" "F.Paste")
			(net "UART_T10_NODE4_RXD_R")
		)
	)
	(footprint ""
		(layer "F.Cu")
		(at 177.649632 -146.90852)
		(property "Reference" "C447"
			(at -5.177282 0.157988 0)
			(unlocked yes)
			(layer "F.SilkS")
			(effects
				(font
					(size 0.7874 0.5842)
					(thickness 0.1524)
				)
				(justify left)
			)
		)
		(property "Value" ""
			(at 0 0 0)
			(layer "F.Fab")
			(effects
				(font
					(size 1.27 1.27)
				)
			)
		)
		(duplicate_pad_numbers_are_jumpers no)
		(fp_line
			(start -1.905 -0.8636)
			(end 1.905 -0.8636)
			(stroke
				(width 0.1524)
				(type default)
			)
			(layer "F.SilkS")
		)
		(fp_line
			(start -1.905 0.8636)
			(end -1.905 -0.8636)
			(stroke
				(width 0.1524)
				(type default)
			)
			(layer "F.SilkS")
		)
		(fp_line
			(start 0 0.8382)
			(end 0 -0.8382)
			(stroke
				(width 0.1524)
				(type default)
			)
			(layer "F.SilkS")
		)
		(fp_line
			(start 1.905 -0.8636)
			(end 1.905 0.8636)
			(stroke
				(width 0.1524)
				(type default)
			)
			(layer "F.SilkS")
		)
		(fp_line
			(start 1.905 0.8636)
			(end -1.905 0.8636)
			(stroke
				(width 0.1524)
				(type default)
			)
			(layer "F.SilkS")
		)
		(fp_rect
			(start -1.524 0.7366)
			(end 1.524 -0.7366)
			(stroke
				(width 0)
				(type default)
			)
			(fill no)
			(layer "F.CrtYd")
		)
		(pad "1" smd rect
			(at 0.94996 0)
			(size 1.1176 1.3716)
			(layers "F.Cu" "F.Mask" "F.Paste")
			(net "P3V3_NODE1")
		)
		(pad "2" smd rect
			(at -0.94996 0)
			(size 1.1176 1.3716)
			(layers "F.Cu" "F.Mask" "F.Paste")
			(net "GND")
		)
	)
)
